# S9S_MB_2U (Grand Teton) — schematic netlist excerpt (pin names and nets, part order shuffled) for the footprints in the layout excerpt that follows; sources: Cadence DE-HDL packaged netlist, KiCad conversion of 03242023_DA0F0TMBIJ0_F0T_Motherboard_J_brd_V01_OCP.brd

R345  Q_RES  0 5% CHIP  pkg 0402LF  page 225 : A = H_CPU1_ERR2_LVC1_R_N ; B = H_CPU_ERR2_LVC1_R_N
C1183  Q_CAP  2.2UF 10V 10% X6S  pkg C0402  page 189 : A = P1V05_PCH_AUX ; B = GND

(kicad_pcb
	(version 20260206)
	(generator "pcbnew")
	(generator_version "10.0")
	(general
		(thickness 1.6)
		(legacy_teardrops no)
	)
	(paper "A4")
	(title_block
		(title "03242023_DA0F0TMBIJ0_F0T_Motherboard_J_brd_V01_OCP.brd")
		(comment 1 "Grand Teton / footprints 5821-5822 of 6105")
	)
	(layers
		(0 "F.Cu" signal "TOP")
		(4 "In1.Cu" signal "GND")
		(6 "In2.Cu" signal "IN1")
		(8 "In3.Cu" signal "GND1")
		(10 "In4.Cu" signal "IN2")
		(12 "In5.Cu" signal "GND2")
		(14 "In6.Cu" signal "IN3")
		(16 "In7.Cu" signal "GND3")
		(18 "In8.Cu" signal "VCC")
		(20 "In9.Cu" signal "VCC1")
		(22 "In10.Cu" signal "GND4")
		(24 "In11.Cu" signal "IN4")
		(26 "In12.Cu" signal "GND5")
		(28 "In13.Cu" signal "IN5")
		(30 "In14.Cu" signal "GND6")
		(32 "In15.Cu" signal "IN6")
		(34 "In16.Cu" signal "GND7")
		(2 "B.Cu" signal "BOTTOM")
		(9 "F.Adhes" user "F.Adhesive")
		(11 "B.Adhes" user "B.Adhesive")
		(13 "F.Paste" user "Package Geometry/Pastemask Top")
		(15 "B.Paste" user "Package Geometry/Pastemask Bottom")
		(5 "F.SilkS" user "Ref Des/Silkscreen Top")
		(7 "B.SilkS" user "Ref Des/Silkscreen Bottom")
		(1 "F.Mask" user "Board Geometry/Soldermask Top")
		(3 "B.Mask" user "Board Geometry/Soldermask Bottom")
		(17 "Dwgs.User" user "User.Drawings")
		(19 "Cmts.User" user "User.Comments")
		(21 "Eco1.User" user "User.Eco1")
		(23 "Eco2.User" user "User.Eco2")
		(25 "Edge.Cuts" user "Board Geometry/Outline")
		(27 "Margin" user)
		(31 "F.CrtYd" user "Package Geometry/Place Bound Top")
		(29 "B.CrtYd" user "Package Geometry/Place Bound Bottom")
		(35 "F.Fab" user "Ref Des/Assembly Top")
		(33 "B.Fab" user "Ref Des/Assembly Bottom")
	)
	(footprint ""
		(layer "B.Cu")
		(at 335.920588 -48.63338 90)
		(property "Reference" "C1183"
			(at 0 0 90)
			(layer "B.SilkS")
			(hide yes)
			(effects
				(font
					(size 1.27 1.27)
				)
				(justify mirror)
			)
		)
		(property "Value" ""
			(at 0 0 90)
			(layer "B.Fab")
			(effects
				(font
					(size 1.27 1.27)
				)
				(justify mirror)
			)
		)
		(duplicate_pad_numbers_are_jumpers no)
		(fp_line
			(start 0.7874 -0.4064)
			(end -0.7874 -0.4064)
			(stroke
				(width 0.1524)
				(type default)
			)
			(layer "B.SilkS")
		)
		(fp_line
			(start -0.7874 -0.4064)
			(end -0.7874 0.4064)
			(stroke
				(width 0.1524)
				(type default)
			)
			(layer "B.SilkS")
		)
		(fp_line
			(start 0.7874 0.4064)
			(end 0.7874 -0.4064)
			(stroke
				(width 0.1524)
				(type default)
			)
			(layer "B.SilkS")
		)
		(fp_line
			(start -0.7874 0.4064)
			(end 0.7874 0.4064)
			(stroke
				(width 0.1524)
				(type default)
			)
			(layer "B.SilkS")
		)
		(fp_line
			(start 0.67945 -0.305054)
			(end 0.12065 -0.305054)
			(stroke
				(width 0.1)
				(type default)
			)
			(layer "B.Fab")
		)
		(fp_line
			(start 0.12065 -0.305054)
			(end 0.12065 -0.2794)
			(stroke
				(width 0.1)
				(type default)
			)
			(layer "B.Fab")
		)
		(fp_line
			(start -0.12065 -0.3048)
			(end -0.67945 -0.3048)
			(stroke
				(width 0.1)
				(type default)
			)
			(layer "B.Fab")
		)
		(fp_line
			(start -0.67945 -0.3048)
			(end -0.67945 0.3048)
			(stroke
				(width 0.1)
				(type default)
			)
			(layer "B.Fab")
		)
		(fp_line
			(start 0.12065 -0.2794)
			(end -0.12065 -0.2794)
			(stroke
				(width 0.1)
				(type default)
			)
			(layer "B.Fab")
		)
		(fp_line
			(start -0.12065 -0.2794)
			(end -0.12065 -0.3048)
			(stroke
				(width 0.1)
				(type default)
			)
			(layer "B.Fab")
		)
		(fp_line
			(start 0.12065 0.2794)
			(end 0.12065 0.3048)
			(stroke
				(width 0.1)
				(type default)
			)
			(layer "B.Fab")
		)
		(fp_line
			(start -0.120396 0.2794)
			(end 0.12065 0.2794)
			(stroke
				(width 0.1)
				(type default)
			)
			(layer "B.Fab")
		)
		(fp_line
			(start 0.67945 0.3048)
			(end 0.67945 -0.305054)
			(stroke
				(width 0.1)
				(type default)
			)
			(layer "B.Fab")
		)
		(fp_line
			(start 0.12065 0.3048)
			(end 0.67945 0.3048)
			(stroke
				(width 0.1)
				(type default)
			)
			(layer "B.Fab")
		)
		(fp_line
			(start -0.120396 0.3048)
			(end -0.120396 0.2794)
			(stroke
				(width 0.1)
				(type default)
			)
			(layer "B.Fab")
		)
		(fp_line
			(start -0.67945 0.3048)
			(end -0.120396 0.3048)
			(stroke
				(width 0.1)
				(type default)
			)
			(layer "B.Fab")
		)
		(pad "1" smd circle
			(at 0.40005 0 270)
			(size 0 0)
			(layers "B.Cu" "B.Mask" "B.Paste")
			(net "P1V05_PCH_AUX")
		)
		(pad "2" smd circle
			(at -0.40005 0 270)
			(size 0 0)
			(layers "B.Cu" "B.Mask" "B.Paste")
			(net "GND")
		)
	)
	(footprint ""
		(layer "B.Cu")
		(at 79.414624 -184.096152 90)
		(property "Reference" "R345"
			(at 0 0 90)
			(layer "B.SilkS")
			(hide yes)
			(effects
				(font
					(size 1.27 1.27)
				)
				(justify mirror)
			)
		)
		(property "Value" ""
			(at 0 0 90)
			(layer "B.Fab")
			(effects
				(font
					(size 1.27 1.27)
				)
				(justify mirror)
			)
		)
		(duplicate_pad_numbers_are_jumpers no)
		(fp_line
			(start 0.7874 -0.4064)
			(end -0.7874 -0.4064)
			(stroke
				(width 0.1524)
				(type default)
			)
			(layer "B.SilkS")
		)
		(fp_line
			(start -0.7874 -0.4064)
			(end -0.7874 0.4064)
			(stroke
				(width 0.1524)
				(type default)
			)
			(layer "B.SilkS")
		)
		(fp_line
			(start 0.7874 0.4064)
			(end 0.7874 -0.4064)
			(stroke
				(width 0.1524)
				(type default)
			)
			(layer "B.SilkS")
		)
		(fp_line
			(start -0.7874 0.4064)
			(end 0.7874 0.4064)
			(stroke
				(width 0.1524)
				(type default)
			)
			(layer "B.SilkS")
		)
		(fp_line
			(start 0.67945 -0.305054)
			(end 0.12065 -0.305054)
			(stroke
				(width 0.1)
				(type default)
			)
			(layer "B.Fab")
		)
		(fp_line
			(start 0.12065 -0.305054)
			(end 0.12065 -0.2794)
			(stroke
				(width 0.1)
				(type default)
			)
			(layer "B.Fab")
		)
		(fp_line
			(start -0.12065 -0.3048)
			(end -0.67945 -0.3048)
			(stroke
				(width 0.1)
				(type default)
			)
			(layer "B.Fab")
		)
		(fp_line
			(start -0.67945 -0.3048)
			(end -0.67945 0.3048)
			(stroke
				(width 0.1)
				(type default)
			)
			(layer "B.Fab")
		)
		(fp_line
			(start 0.12065 -0.2794)
			(end -0.12065 -0.2794)
			(stroke
				(width 0.1)
				(type default)
			)
			(layer "B.Fab")
		)
		(fp_line
			(start -0.12065 -0.2794)
			(end -0.12065 -0.3048)
			(stroke
				(width 0.1)
				(type default)
			)
			(layer "B.Fab")
		)
		(fp_line
			(start 0.12065 0.2794)
			(end 0.12065 0.3048)
			(stroke
				(width 0.1)
				(type default)
			)
			(layer "B.Fab")
		)
		(fp_line
			(start -0.120396 0.2794)
			(end 0.12065 0.2794)
			(stroke
				(width 0.1)
				(type default)
			)
			(layer "B.Fab")
		)
		(fp_line
			(start 0.67945 0.3048)
			(end 0.67945 -0.305054)
			(stroke
				(width 0.1)
				(type default)
			)
			(layer "B.Fab")
		)
		(fp_line
			(start 0.12065 0.3048)
			(end 0.67945 0.3048)
			(stroke
				(width 0.1)
				(type default)
			)
			(layer "B.Fab")
		)
		(fp_line
			(start -0.120396 0.3048)
			(end -0.120396 0.2794)
			(stroke
				(width 0.1)
				(type default)
			)
			(layer "B.Fab")
		)
		(fp_line
			(start -0.67945 0.3048)
			(end -0.120396 0.3048)
			(stroke
				(width 0.1)
				(type default)
			)
			(layer "B.Fab")
		)
		(pad "1" smd circle
			(at 0.40005 0 270)
			(size 0 0)
			(layers "B.Cu" "B.Mask" "B.Paste")
			(net "H_CPU1_ERR2_LVC1_R_N")
		)
		(pad "2" smd circle
			(at -0.40005 0 270)
			(size 0 0)
			(layers "B.Cu" "B.Mask" "B.Paste")
			(net "H_CPU_ERR2_LVC1_R_N")
		)
	)
)
